(kicad_pcb
	(version 20260206)
	(generator "pcbnew")
	(generator_version "10.0")
	(general
		(thickness 1.6)
		(legacy_teardrops no)
	)
	(paper "A4")
	(title_block
		(title "m-2 — Lightning_M.2_BRD.brd")
		(comment 1 "Lightning (Wiwynn / Facebook NVMe JBOF) / footprint 146 of 157 (SKT1), pads 1-72 of 72")
	)
	(layers
		(0 "F.Cu" signal "TOP")
		(4 "In1.Cu" signal "L2GND")
		(6 "In2.Cu" signal "L3")
		(8 "In3.Cu" signal "L4GND")
		(10 "In4.Cu" signal "L5GND")
		(12 "In5.Cu" signal "L6")
		(14 "In6.Cu" signal "L7GND")
		(2 "B.Cu" signal "BOTTOM")
		(9 "F.Adhes" user "F.Adhesive")
		(11 "B.Adhes" user "B.Adhesive")
		(13 "F.Paste" user "Package Geometry/Pastemask Top")
		(15 "B.Paste" user "Package Geometry/Pastemask Bottom")
		(5 "F.SilkS" user "Ref Des/Silkscreen Top")
		(7 "B.SilkS" user "Ref Des/Silkscreen Bottom")
		(1 "F.Mask" user "Board Geometry/Soldermask Top")
		(3 "B.Mask" user "Board Geometry/Soldermask Bottom")
		(17 "Dwgs.User" user "User.Drawings")
		(19 "Cmts.User" user "User.Comments")
		(21 "Eco1.User" user "User.Eco1")
		(23 "Eco2.User" user "User.Eco2")
		(25 "Edge.Cuts" user "Board Geometry/Outline")
		(27 "Margin" user)
		(31 "F.CrtYd" user "Package Geometry/Place Bound Top")
		(29 "B.CrtYd" user "Package Geometry/Place Bound Bottom")
		(35 "F.Fab" user "Ref Des/Assembly Top")
		(33 "B.Fab" user "Ref Des/Assembly Bottom")
	)
	(footprint ""
		(layer "B.Cu")
		(at 79.149956 -27.595068 90)
		(property "Reference" "SKT1"
			(at 0 0 90)
			(layer "B.SilkS")
			(hide yes)
			(effects
				(font
					(size 1.27 1.27)
				)
				(justify mirror)
			)
		)
		(property "Value" "SKT-SAS28-P15-PCIE25-2-GP"
			(at -10.668 -4.2672 90)
			(unlocked yes)
			(layer "B.Fab")
			(hide yes)
			(effects
				(font
					(size 1.016 1.016)
					(thickness 0.1524)
				)
				(justify mirror)
			)
		)
		(property "Device Type" "78758-0001"
			(at -10.668 -5.7912 90)
			(unlocked yes)
			(layer "B.Fab")
			(hide yes)
			(effects
				(font
					(size 1.016 1.016)
					(thickness 0.1524)
				)
				(justify mirror)
			)
		)
		(duplicate_pad_numbers_are_jumpers no)
		(pad "" np_thru_hole circle
			(at -19.500088 0 270)
			(size 0.254 0.254)
			(drill 1.6002)
			(layers "*.Cu" "*.Mask")
			(clearance 1.0287)
			(thermal_gap 1.0287)
		)
		(pad "" np_thru_hole circle
			(at 19.500088 0 270)
			(size 0.254 0.254)
			(drill 1.651)
			(layers "*.Cu" "*.Mask")
			(clearance 1.0541)
			(thermal_gap 1.0541)
		)
		(pad "E1" smd rect
			(at 7.055104 -0.379984 270)
			(size 0.508 1.7526)
			(layers "B.Cu" "B.Mask" "B.Paste")
			(net "D85_PCIE_B_REFCLK_P")
		)
		(pad "E2" smd rect
			(at 6.255004 -0.379984 270)
			(size 0.508 1.7526)
			(layers "B.Cu" "B.Mask" "B.Paste")
			(net "D85_PCIE_B_REFCLK_N")
		)
		(pad "E3" smd rect
			(at 5.455158 -0.379984 270)
			(size 0.508 1.7526)
			(layers "B.Cu" "B.Mask" "B.Paste")
			(net "P3V3_DPB")
		)
		(pad "E4" smd rect
			(at 4.655058 -0.379984 270)
			(size 0.508 1.7526)
			(layers "B.Cu" "B.Mask" "B.Paste")
			(net "Z50_DEV_RST#")
		)
		(pad "E5" smd rect
			(at 3.855212 -0.379984 270)
			(size 0.508 1.7526)
			(layers "B.Cu" "B.Mask" "B.Paste")
			(net "Z50_DEV_RST#")
		)
		(pad "E6" smd rect
			(at 3.055112 -0.379984 270)
			(size 0.508 1.7526)
			(layers "B.Cu" "B.Mask" "B.Paste")
			(net "Net_165")
		)
		(pad "E7" smd rect
			(at 15.48003 2.23012 270)
			(size 0.508 1.7526)
			(layers "B.Cu" "B.Mask" "B.Paste")
			(net "D85_PCIE_A_REFCLK_P")
		)
		(pad "E8" smd rect
			(at 14.67993 2.23012 270)
			(size 0.508 1.7526)
			(layers "B.Cu" "B.Mask" "B.Paste")
			(net "D85_PCIE_A_REFCLK_N")
		)
		(pad "E9" smd rect
			(at 13.880084 2.23012 270)
			(size 0.508 1.7526)
			(layers "B.Cu" "B.Mask" "B.Paste")
			(net "GND")
		)
		(pad "E10" smd rect
			(at 13.079984 2.23012 270)
			(size 0.508 1.7526)
			(layers "B.Cu" "B.Mask" "B.Paste")
			(net "D85_PCIE_A_TX0_P")
		)
		(pad "E11" smd rect
			(at 12.279884 2.23012 270)
			(size 0.508 1.7526)
			(layers "B.Cu" "B.Mask" "B.Paste")
			(net "D85_PCIE_A_TX0_N")
		)
		(pad "E12" smd rect
			(at 11.480038 2.23012 270)
			(size 0.508 1.7526)
			(layers "B.Cu" "B.Mask" "B.Paste")
			(net "GND")
		)
		(pad "E13" smd rect
			(at 10.679938 2.23012 270)
			(size 0.508 1.7526)
			(layers "B.Cu" "B.Mask" "B.Paste")
			(net "D85_PCIE_A_RX0_N")
		)
		(pad "E14" smd rect
			(at 9.880092 2.23012 270)
			(size 0.508 1.7526)
			(layers "B.Cu" "B.Mask" "B.Paste")
			(net "D85_PCIE_A_RX0_P")
		)
		(pad "E15" smd rect
			(at 9.079992 2.23012 270)
			(size 0.508 1.7526)
			(layers "B.Cu" "B.Mask" "B.Paste")
			(net "GND")
		)
		(pad "E16" smd rect
			(at 8.279892 2.23012 270)
			(size 0.508 1.7526)
			(layers "B.Cu" "B.Mask" "B.Paste")
			(net "Net_169")
		)
		(pad "E17" smd rect
			(at -9.320022 2.23012 270)
			(size 0.508 1.7526)
			(layers "B.Cu" "B.Mask" "B.Paste")
			(net "D85_PCIE_B_TX1_P")
		)
		(pad "E18" smd rect
			(at -10.120122 2.23012 270)
			(size 0.508 1.7526)
			(layers "B.Cu" "B.Mask" "B.Paste")
			(net "D85_PCIE_B_TX1_N")
		)
		(pad "E19" smd rect
			(at -10.919968 2.23012 270)
			(size 0.508 1.7526)
			(layers "B.Cu" "B.Mask" "B.Paste")
			(net "GND")
		)
		(pad "E20" smd rect
			(at -11.720068 2.23012 270)
			(size 0.508 1.7526)
			(layers "B.Cu" "B.Mask" "B.Paste")
			(net "D85_PCIE_B_RX1_N")
		)
		(pad "E21" smd rect
			(at -12.519914 2.23012 270)
			(size 0.508 1.7526)
			(layers "B.Cu" "B.Mask" "B.Paste")
			(net "D85_PCIE_B_RX1_P")
		)
		(pad "E22" smd rect
			(at -13.320014 2.23012 270)
			(size 0.508 1.7526)
			(layers "B.Cu" "B.Mask" "B.Paste")
			(net "GND")
		)
		(pad "E23" smd rect
			(at -14.120114 2.23012 270)
			(size 0.508 1.7526)
			(layers "B.Cu" "B.Mask" "B.Paste")
			(net "Z50_SMB_CLK")
		)
		(pad "E24" smd rect
			(at -14.91996 2.23012 270)
			(size 0.508 1.7526)
			(layers "B.Cu" "B.Mask" "B.Paste")
			(net "Z50_SMB_DATA")
		)
		(pad "E25" smd rect
			(at -15.72006 2.23012 270)
			(size 0.508 1.7526)
			(layers "B.Cu" "B.Mask" "B.Paste")
			(net "Net_157")
		)
		(pad "G1" smd rect
			(at 24.21509 5.750052 270)
			(size 3.81 3.9878)
			(layers "B.Cu" "B.Mask" "B.Paste")
			(net "GND")
		)
		(pad "G2" smd rect
			(at -24.21509 5.750052 270)
			(size 3.81 3.9878)
			(layers "B.Cu" "B.Mask" "B.Paste")
			(net "GND")
		)
		(pad "P1" smd rect
			(at 1.905 -0.329946 270)
			(size 0.889 1.8542)
			(layers "B.Cu" "B.Mask" "B.Paste")
			(net "Net_162")
		)
		(pad "P2" smd rect
			(at 0.635 -0.329946 270)
			(size 0.889 1.8542)
			(layers "B.Cu" "B.Mask" "B.Paste")
			(net "Net_163")
		)
		(pad "P3" smd rect
			(at -0.635 -0.329946 270)
			(size 0.889 1.8542)
			(layers "B.Cu" "B.Mask" "B.Paste")
			(net "Net_164")
		)
		(pad "P4" smd rect
			(at -1.905 -0.329946 270)
			(size 0.889 1.8542)
			(layers "B.Cu" "B.Mask" "B.Paste")
			(net "Z50_SSD_M2_PRSNT#")
		)
		(pad "P5" smd rect
			(at -3.175 -0.329946 270)
			(size 0.889 1.8542)
			(layers "B.Cu" "B.Mask" "B.Paste")
			(net "GND")
		)
		(pad "P6" smd rect
			(at -4.445 -0.329946 270)
			(size 0.889 1.8542)
			(layers "B.Cu" "B.Mask" "B.Paste")
			(net "GND")
		)
		(pad "P7" smd rect
			(at -5.715 -0.329946 270)
			(size 0.889 1.8542)
			(layers "B.Cu" "B.Mask" "B.Paste")
			(net "Net_159")
		)
		(pad "P8" smd rect
			(at -6.985 -0.329946 270)
			(size 0.889 1.8542)
			(layers "B.Cu" "B.Mask" "B.Paste")
			(net "Net_160")
		)
		(pad "P9" smd rect
			(at -8.255 -0.329946 270)
			(size 0.889 1.8542)
			(layers "B.Cu" "B.Mask" "B.Paste")
			(net "Net_161")
		)
		(pad "P10" smd rect
			(at -9.525 -0.329946 270)
			(size 0.889 1.8542)
			(layers "B.Cu" "B.Mask" "B.Paste")
			(net "Z50_SSD_M2_PRSNT#")
		)
		(pad "P11" smd rect
			(at -10.795 -0.329946 270)
			(size 0.889 1.8542)
			(layers "B.Cu" "B.Mask" "B.Paste")
			(net "Z50_SSD_ACT#")
		)
		(pad "P12" smd rect
			(at -12.065 -0.329946 270)
			(size 0.889 1.8542)
			(layers "B.Cu" "B.Mask" "B.Paste")
			(net "GND")
		)
		(pad "P13" smd rect
			(at -13.335 -0.329946 270)
			(size 0.889 1.8542)
			(layers "B.Cu" "B.Mask" "B.Paste")
			(net "P12V")
		)
		(pad "P14" smd rect
			(at -14.605 -0.329946 270)
			(size 0.889 1.8542)
			(layers "B.Cu" "B.Mask" "B.Paste")
			(net "P12V")
		)
		(pad "P15" smd rect
			(at -15.875 -0.329946 270)
			(size 0.889 1.8542)
			(layers "B.Cu" "B.Mask" "B.Paste")
			(net "P12V")
		)
		(pad "S1" smd rect
			(at 15.875 -0.329946 270)
			(size 0.889 1.8542)
			(layers "B.Cu" "B.Mask" "B.Paste")
			(net "GND")
		)
		(pad "S2" smd rect
			(at 14.605 -0.329946 270)
			(size 0.889 1.8542)
			(layers "B.Cu" "B.Mask" "B.Paste")
			(net "Net_173")
		)
		(pad "S3" smd rect
			(at 13.335 -0.329946 270)
			(size 0.889 1.8542)
			(layers "B.Cu" "B.Mask" "B.Paste")
			(net "Net_174")
		)
		(pad "S4" smd rect
			(at 12.065 -0.329946 270)
			(size 0.889 1.8542)
			(layers "B.Cu" "B.Mask" "B.Paste")
			(net "GND")
		)
		(pad "S5" smd rect
			(at 10.795 -0.329946 270)
			(size 0.889 1.8542)
			(layers "B.Cu" "B.Mask" "B.Paste")
			(net "Net_167")
		)
		(pad "S6" smd rect
			(at 9.525 -0.329946 270)
			(size 0.889 1.8542)
			(layers "B.Cu" "B.Mask" "B.Paste")
			(net "Net_168")
		)
		(pad "S7" smd rect
			(at 8.255 -0.329946 270)
			(size 0.889 1.8542)
			(layers "B.Cu" "B.Mask" "B.Paste")
			(net "GND")
		)
		(pad "S8" smd rect
			(at 7.480046 2.23012 270)
			(size 0.508 1.7526)
			(layers "B.Cu" "B.Mask" "B.Paste")
			(net "GND")
		)
		(pad "S9" smd rect
			(at 6.679946 2.23012 270)
			(size 0.508 1.7526)
			(layers "B.Cu" "B.Mask" "B.Paste")
			(net "Net_170")
		)
		(pad "S10" smd rect
			(at 5.8801 2.23012 270)
			(size 0.508 1.7526)
			(layers "B.Cu" "B.Mask" "B.Paste")
			(net "Net_171")
		)
		(pad "S11" smd rect
			(at 5.08 2.23012 270)
			(size 0.508 1.7526)
			(layers "B.Cu" "B.Mask" "B.Paste")
			(net "GND")
		)
		(pad "S12" smd rect
			(at 4.2799 2.23012 270)
			(size 0.508 1.7526)
			(layers "B.Cu" "B.Mask" "B.Paste")
			(net "Net_172")
		)
		(pad "S13" smd rect
			(at 3.480054 2.23012 270)
			(size 0.508 1.7526)
			(layers "B.Cu" "B.Mask" "B.Paste")
			(net "Net_166")
		)
		(pad "S14" smd rect
			(at 2.679954 2.23012 270)
			(size 0.508 1.7526)
			(layers "B.Cu" "B.Mask" "B.Paste")
			(net "GND")
		)
		(pad "S15" smd rect
			(at 1.880108 2.23012 270)
			(size 0.508 1.7526)
			(layers "B.Cu" "B.Mask" "B.Paste")
			(net "Net_44")
		)
		(pad "S16" smd rect
			(at 1.080008 2.23012 270)
			(size 0.508 1.7526)
			(layers "B.Cu" "B.Mask" "B.Paste")
			(net "GND")
		)
		(pad "S17" smd rect
			(at 0.279908 2.23012 270)
			(size 0.508 1.7526)
			(layers "B.Cu" "B.Mask" "B.Paste")
			(net "D85_PCIE_A_TX1_P")
		)
		(pad "S18" smd rect
			(at -0.519938 2.23012 270)
			(size 0.508 1.7526)
			(layers "B.Cu" "B.Mask" "B.Paste")
			(net "D85_PCIE_A_TX1_N")
		)
		(pad "S19" smd rect
			(at -1.320038 2.23012 270)
			(size 0.508 1.7526)
			(layers "B.Cu" "B.Mask" "B.Paste")
			(net "GND")
		)
		(pad "S20" smd rect
			(at -2.119884 2.23012 270)
			(size 0.508 1.7526)
			(layers "B.Cu" "B.Mask" "B.Paste")
			(net "D85_PCIE_A_RX1_N")
		)
		(pad "S21" smd rect
			(at -2.919984 2.23012 270)
			(size 0.508 1.7526)
			(layers "B.Cu" "B.Mask" "B.Paste")
			(net "D85_PCIE_A_RX1_P")
		)
		(pad "S22" smd rect
			(at -3.720084 2.23012 270)
			(size 0.508 1.7526)
			(layers "B.Cu" "B.Mask" "B.Paste")
			(net "GND")
		)
		(pad "S23" smd rect
			(at -4.51993 2.23012 270)
			(size 0.508 1.7526)
			(layers "B.Cu" "B.Mask" "B.Paste")
			(net "D85_PCIE_B_TX0_P")
		)
		(pad "S24" smd rect
			(at -5.32003 2.23012 270)
			(size 0.508 1.7526)
			(layers "B.Cu" "B.Mask" "B.Paste")
			(net "D85_PCIE_B_TX0_N")
		)
		(pad "S25" smd rect
			(at -6.119876 2.23012 270)
			(size 0.508 1.7526)
			(layers "B.Cu" "B.Mask" "B.Paste")
			(net "GND")
		)
		(pad "S26" smd rect
			(at -6.919976 2.23012 270)
			(size 0.508 1.7526)
			(layers "B.Cu" "B.Mask" "B.Paste")
			(net "D85_PCIE_B_RX0_N")
		)
		(pad "S27" smd rect
			(at -7.720076 2.23012 270)
			(size 0.508 1.7526)
			(layers "B.Cu" "B.Mask" "B.Paste")
			(net "D85_PCIE_B_RX0_P")
		)
		(pad "S28" smd rect
			(at -8.519922 2.23012 270)
			(size 0.508 1.7526)
			(layers "B.Cu" "B.Mask" "B.Paste")
			(net "GND")
		)
	)
)
